;LEADER: 12 
;HEADER: 
;CODE  : ASCII 
;FILE  : 9127_F0T_Expander_BD_F_v02_0110_1240-bd-18-7.drl for backdrilling ... from layer BOTTOM to layer GND2
;DESIGN: 9127_F0T_Expander_BD_F_v02_0110_1240.brd
;MUST-NOT-CUT-LAYER = IN1,  MAX_DRILL_DEPTH = 84.05 MILS,  MFG_STUB_LENGTH = 0.00 MILS
;   BackdrillSize 1. = 15.700000 Tolerance = +0.000000/-0.000000 NON_PLATED MILS Quantity = 512
;   BackdrillSize 2. = 17.700000 Tolerance = +0.000000/-0.000000 NON_PLATED MILS Quantity = 268
;   BackdrillSize 3. = 19.900000 Tolerance = +0.000000/-0.000000 NON_PLATED MILS Quantity = 256
%
G90
X0167519Y1250984
X0163779Y1247243
X0160039Y1250984
X0163779Y1243503
X0156299Y1247243
X0156299Y1243503
X0160039Y1254724
X0167519Y1254724
X0152559Y1254724
X0152559Y1250984
X0145078Y1247243
X0148818Y1247243
X0152559Y1217322
X0152559Y1187401
X0152559Y1209842
X0148818Y1206102
X0156299Y1209842
X0152559Y1194881
X0145078Y1206102
X0148818Y1198621
X0148818Y1191141
X0152559Y1202362
X0145078Y1191141
X0156299Y1187401
X0145078Y1198621
X0156299Y1194881
X0156299Y1217322
X0145078Y1213582
X0148818Y1213582
X0156299Y1202362
X0148818Y1221062
X0145078Y1221062
X0264762Y1075196
X0264762Y1078936
X0242321Y1075196
X0257282Y1075196
X0238581Y1086416
X0268502Y1086416
X0261022Y1082677
X0253542Y1086416
X0246061Y1086417
X0268502Y1082676
X0234841Y1078935
X0238581Y1082676
X0234841Y1075195
X0246061Y1082677
X0249802Y1075196
X0257282Y1078936
X0253542Y1082676
X0261022Y1086417
X0242321Y1078936
X0249802Y1078936
X0186220Y1243503
X0186220Y1247243
X0189960Y1250984
X0189960Y1254724
X0193700Y1243503
X0193700Y1247243
X0197440Y1250984
X0197440Y1254724
X0178740Y1243503
X0174999Y1254724
X0171259Y1243503
X0174999Y1250984
X0171259Y1247243
X0182480Y1250984
X0182480Y1254724
X0178740Y1247243
X0261023Y1247243
X0261023Y1243503
X0268503Y1247243
X0268503Y1243503
X0264763Y1250984
X0264763Y1254724
X0279724Y1254724
X0287204Y1250984
X0283464Y1247243
X0279724Y1250984
X0283464Y1243503
X0275984Y1247243
X0287204Y1254724
X0275984Y1243503
X0272244Y1250984
X0272244Y1254724
X0320866Y1131299
X0317125Y1127558
X0320866Y1123818
X0324606Y1131299
X0313385Y1135039
X0317125Y1135039
X0324606Y1123818
X0313385Y1127558
X0309644Y1075196
X0320866Y1082676
X0302164Y1075196
X0320866Y1116338
X0317125Y1120078
X0298424Y1082676
X0313384Y1086417
X0317124Y1075196
X0298424Y1086416
X0313384Y1082677
X0313385Y1112598
X0324606Y1116338
X0317125Y1112598
X0320866Y1108858
X0309644Y1078936
X0294684Y1078936
X0317124Y1078936
X0305904Y1086417
X0302164Y1078936
X0324606Y1108858
X0294684Y1075196
X0324606Y1082676
X0305904Y1082677
X0313385Y1120078
X0272243Y1075196
X0283463Y1086416
X0279723Y1078936
X0272243Y1078936
X0279723Y1075196
X0283463Y1082676
X0287203Y1075196
X0290943Y1082677
X0287203Y1078936
X0275982Y1086417
X0275982Y1082677
X0290943Y1086417
X0658268Y1243503
X0665748Y1243503
X0662008Y1250984
X0658268Y1247243
X0665748Y1247243
X0662008Y1254724
X0755512Y1247243
X0748031Y1243503
X0759252Y1250984
X0766732Y1254724
X0748031Y1247243
X0759252Y1254724
X0751772Y1254724
X0751772Y1250984
X0762992Y1247243
X0762992Y1243503
X0755512Y1243503
X0766732Y1250984
X0680709Y1243503
X0669488Y1254724
X0676968Y1250984
X0676968Y1254724
X0684449Y1250984
X0684449Y1254724
X0673228Y1247243
X0669488Y1250984
X0680709Y1247243
X0673228Y1243503
X0695669Y1243503
X0699409Y1250984
X0695669Y1247243
X0703149Y1247243
X0710630Y1243503
X0706890Y1254724
X0691929Y1254724
X0710630Y1247243
X0714370Y1250984
X0714370Y1254724
X0703149Y1243503
X0688189Y1243503
X0688189Y1247243
X0691929Y1250984
X0706890Y1250984
X0699409Y1254724
X0751771Y1078936
X0762991Y1082677
X0755511Y1082676
X0759251Y1078936
X0755511Y1086416
X0766731Y1078936
X0759251Y1075196
X0766731Y1075196
X0762991Y1086417
X0751771Y1075196
X0748030Y1082677
X0725589Y1082676
X0729330Y1075196
X0744290Y1075196
X0714369Y1075196
X0721849Y1075196
X0710629Y1082676
X0733069Y1082677
X0736810Y1078936
X0718109Y1082677
X0695668Y1082676
X0729330Y1078936
X0703148Y1086417
X0691928Y1075195
X0740550Y1082676
X0710629Y1086416
X0721849Y1078936
X0703148Y1082677
X0740550Y1086416
X0748030Y1086417
X0714369Y1078936
X0718109Y1086417
X0733069Y1086417
X0706889Y1078936
X0699408Y1075196
X0736810Y1075196
X0725589Y1086416
X0695668Y1086416
X0699408Y1078936
X0706889Y1075196
X0744290Y1078936
X0691928Y1078935
X0777953Y1082676
X0774212Y1120078
X0777953Y1116338
X0770471Y1082677
X0774211Y1075196
X0770471Y1086417
X0781693Y1108858
X0770472Y1120078
X0777953Y1108858
X0774211Y1078936
X0781693Y1116338
X0770472Y1112598
X0781693Y1082676
X0774212Y1112598
X0777953Y1198621
X0770472Y1202362
X0777953Y1213582
X0774212Y1217322
X0774212Y1202362
X0770472Y1217322
X0781693Y1206102
X0781693Y1221062
X0777953Y1221062
X0774212Y1209842
X0781693Y1213582
X0770472Y1209842
X0781693Y1198621
X0777953Y1206102
X0777953Y1131299
X0774212Y1135039
X0777953Y1123818
X0774212Y1127558
X0781693Y1123818
X0781693Y1131299
X0770472Y1135039
X0770472Y1127558
X0774212Y1254724
X0774212Y1250984
X0770472Y1247243
X0781693Y1247243
X0770472Y1243503
X0777953Y1247243
X1059251Y1191141
X1066732Y1202362
X1059251Y1213582
X1066732Y1187401
X1059251Y1206102
X1066732Y1209842
X1062991Y1213582
X1062991Y1206102
X1062991Y1191141
X1066732Y1194881
X1059251Y1198621
X1062991Y1198621
X1062991Y1221062
X1066732Y1217322
X1059251Y1221062
X1066732Y1250984
X1062991Y1247243
X1059251Y1247243
X1066732Y1254724
X1104133Y1250984
X1111613Y1250984
X1085432Y1247243
X1100393Y1247243
X1107873Y1247243
X1100393Y1243503
X1107873Y1243503
X1089172Y1250984
X1092913Y1243503
X1089172Y1254724
X1096653Y1250984
X1092913Y1247243
X1085432Y1243503
X1111613Y1254724
X1104133Y1254724
X1096653Y1254724
X1081692Y1254724
X1077952Y1247243
X1081692Y1250984
X1070472Y1243503
X1077952Y1243503
X1074212Y1254724
X1070472Y1247243
X1074212Y1250984
X1070472Y1202362
X1070472Y1209842
X1070472Y1194881
X1070472Y1187401
X1070472Y1217322
X1167715Y1082676
X1152754Y1082676
X1160234Y1082677
X1152754Y1086416
X1149014Y1075195
X1156494Y1078936
X1163975Y1078936
X1167715Y1086416
X1163975Y1075196
X1160234Y1086417
X1149014Y1078935
X1156494Y1075196
X1186416Y1078936
X1197636Y1086416
X1182675Y1082676
X1201376Y1075196
X1186416Y1075196
X1171455Y1078936
X1201376Y1078936
X1205116Y1086417
X1171455Y1075196
X1193896Y1078936
X1178935Y1078936
X1175195Y1082677
X1197636Y1082676
X1190155Y1082677
X1182675Y1086416
X1205116Y1082677
X1193896Y1075196
X1178935Y1075196
X1175195Y1086417
X1190155Y1086417
X1220077Y1082677
X1227557Y1082677
X1208857Y1075196
X1216337Y1078936
X1208857Y1078936
X1223817Y1075196
X1227558Y1120078
X1231297Y1075196
X1238779Y1082676
X1235039Y1116338
X1223817Y1078936
X1235039Y1108858
X1231298Y1112598
X1227557Y1086417
X1235039Y1082676
X1231298Y1120078
X1238779Y1116338
X1216337Y1075196
X1231297Y1078936
X1220077Y1086417
X1212597Y1086416
X1238779Y1108858
X1227558Y1112598
X1212597Y1082676
X1238779Y1123818
X1227558Y1135039
X1231298Y1127558
X1235039Y1131299
X1238779Y1131299
X1227558Y1127558
X1235039Y1123818
X1231298Y1135039
X1175196Y1247243
X1186417Y1254724
X1190157Y1247243
X1193897Y1254724
X1197637Y1243503
X1201377Y1254724
X1193897Y1250984
X1182676Y1243503
X1186417Y1250984
X1178936Y1250984
X1197637Y1247243
X1182676Y1247243
X1175196Y1243503
X1201377Y1250984
X1178936Y1254724
X1190157Y1243503
X1665944Y1075196
X1665944Y1078936
X1621062Y1075196
X1658463Y1078936
X1624802Y1086416
X1639762Y1082676
X1617321Y1086417
X1662203Y1082677
X1621062Y1078936
X1647242Y1086417
X1647242Y1082677
X1617321Y1082677
X1606101Y1075195
X1628542Y1075196
X1650983Y1078936
X1609841Y1082676
X1636022Y1078936
X1658463Y1075196
X1654723Y1082676
X1643503Y1075196
X1624802Y1082676
X1650983Y1075196
X1636022Y1075196
X1632282Y1086417
X1639762Y1086416
X1628542Y1078936
X1654723Y1086416
X1606101Y1078935
X1643503Y1078936
X1613581Y1078936
X1609841Y1086416
X1613581Y1075196
X1632282Y1082677
X1662203Y1086417
X1665945Y1250984
X1662204Y1243503
X1665945Y1254724
X1662204Y1247243
X1621063Y1250984
X1602362Y1243503
X1613582Y1254724
X1628543Y1254724
X1602362Y1247243
X1617322Y1247243
X1628543Y1250984
X1609842Y1243503
X1617322Y1243503
X1606102Y1254724
X1613582Y1250984
X1621063Y1254724
X1624803Y1243503
X1606102Y1250984
X1624803Y1247243
X1609842Y1247243
X1591141Y1250984
X1583661Y1250984
X1594882Y1247243
X1579921Y1243503
X1572441Y1243503
X1576181Y1250984
X1598622Y1250984
X1594882Y1243503
X1598622Y1254724
X1587401Y1243503
X1587401Y1247243
X1591141Y1254724
X1576181Y1254724
X1579921Y1247243
X1583661Y1254724
X1572441Y1247243
X1680905Y1250984
X1695866Y1247243
X1669685Y1243503
X1669685Y1247243
X1680905Y1254724
X1688385Y1250984
X1688385Y1254724
X1677165Y1247243
X1673425Y1254724
X1684645Y1247243
X1692126Y1247243
X1677165Y1243503
X1684645Y1243503
X1673425Y1250984
X1695866Y1198621
X1688385Y1217322
X1695866Y1206102
X1688385Y1209842
X1692126Y1221062
X1692126Y1206102
X1695866Y1213582
X1684645Y1209842
X1695866Y1221062
X1684645Y1217322
X1688385Y1202362
X1692126Y1198621
X1692126Y1213582
X1684645Y1202362
X1688385Y1135039
X1688385Y1127558
X1692126Y1131299
X1692126Y1123818
X1684645Y1127558
X1695866Y1131299
X1684645Y1135039
X1695866Y1123818
X1688385Y1112598
X1677164Y1082677
X1695866Y1108858
X1669684Y1082676
X1695866Y1116338
X1695866Y1082676
X1677164Y1086417
X1684645Y1112598
X1673424Y1078936
X1688385Y1120078
X1688384Y1075196
X1688384Y1078936
X1680904Y1078936
X1680904Y1075196
X1684644Y1086417
X1684645Y1120078
X1669684Y1086416
X1684644Y1082677
X1673424Y1075196
X1692126Y1082676
X1692126Y1108858
X1692126Y1116338
M00
X0212980Y0408568
X0205680Y0398082
X0205680Y0412255
X0212980Y0390995
X0205680Y0401482
X0212980Y0394395
X0205680Y0415655
X0212980Y0405168
X0212980Y0419341
X0256705Y0477824
X0264005Y0481510
X0256705Y0491997
X0256705Y0521958
X0264005Y0511471
X0256705Y0474424
X0256705Y0518558
X0264005Y0470737
X0264005Y0467337
X0256705Y0488597
X0264005Y0484910
X0264005Y0514871
X0212980Y0486954
X0212980Y0472781
X0205680Y0520602
X0212980Y0469381
X0212980Y0436915
X0212980Y0513515
X0205680Y0476468
X0212980Y0483554
X0205680Y0444002
X0205680Y0426428
X0212980Y0516915
X0205680Y0479868
X0205680Y0490641
X0212980Y0422741
X0212980Y0433515
X0205680Y0429828
X0205680Y0494041
X0205680Y0440602
X0256705Y0582771
X0264005Y0564910
X0256705Y0596944
X0264005Y0604030
X0264005Y0579084
X0256705Y0568597
X0264005Y0607430
X0264005Y0575684
X0264005Y0529044
X0264005Y0525644
X0256705Y0536131
X0256705Y0586171
X0256705Y0614517
X0256705Y0571997
X0264005Y0593257
X0256705Y0600344
X0256705Y0532731
X0256705Y0611117
X0264005Y0561510
X0264005Y0589857
X0205680Y0524002
X0212980Y0531088
X0205680Y0538175
X0212980Y0527688
X0205680Y0534775
X0662766Y0401482
X0662766Y0412255
X0662766Y0415655
X0662766Y0398082
X0662766Y0479868
X0662766Y0429828
X0662766Y0494041
X0662766Y0444002
X0662766Y0426428
X0662766Y0520602
X0662766Y0440602
X0662766Y0490641
X0662766Y0476468
X0662766Y0538175
X0662766Y0524002
X0662766Y0534775
X0713791Y0614517
X0721091Y0589857
X0721091Y0604030
X0713791Y0600344
X0721091Y0607430
X0721091Y0564910
X0713791Y0586171
X0721091Y0575684
X0713791Y0568597
X0721091Y0579084
X0713791Y0596944
X0713791Y0532731
X0713791Y0582771
X0713791Y0536131
X0721091Y0593257
X0713791Y0571997
X0713791Y0611117
X0721091Y0529044
X0721091Y0561510
X0721091Y0525644
X0670066Y0531088
X0670066Y0527688
X0713791Y0477824
X0721091Y0511471
X0713791Y0521958
X0721091Y0467337
X0721091Y0514871
X0713791Y0518558
X0713791Y0491997
X0721091Y0481510
X0713791Y0488597
X0713791Y0474424
X0721091Y0470737
X0721091Y0484910
X0670066Y0486954
X0670066Y0436915
X0670066Y0472781
X0670066Y0513515
X0670066Y0483554
X0670066Y0469381
X0670066Y0433515
X0670066Y0516915
X0670066Y0422741
X0670066Y0394395
X0670066Y0419341
X0670066Y0408568
X0670066Y0405168
X0670066Y0390995
X0919163Y0848442
X0949382Y0886737
X0919163Y0851592
X0945982Y0886737
X1011187Y-0030126
X1011187Y-0033526
X1127153Y0531088
X1127153Y0527688
X1119853Y0534775
X1119853Y0524002
X1119853Y0538175
X1127153Y0483554
X1119853Y0520602
X1119853Y0479868
X1119853Y0429828
X1127153Y0486954
X1127153Y0433515
X1127153Y0436915
X1127153Y0513515
X1127153Y0469381
X1119853Y0426428
X1119853Y0444002
X1127153Y0422741
X1119853Y0494041
X1119853Y0476468
X1127153Y0516915
X1127153Y0472781
X1119853Y0440602
X1119853Y0490641
X1119853Y0401482
X1119853Y0415655
X1119853Y0398082
X1127153Y0394395
X1127153Y0405168
X1127153Y0419341
X1119853Y0412255
X1127153Y0390995
X1127153Y0408568
X1081187Y-0069306
X1081187Y-0072706
X1225405Y-0069278
X1230761Y-0030228
X1230761Y-0033628
X1225405Y-0072678
X1170878Y0488597
X1178178Y0470737
X1178178Y0481510
X1178178Y0514871
X1170878Y0477824
X1170878Y0521958
X1170878Y0474424
X1178178Y0511471
X1170878Y0518558
X1178178Y0484910
X1170878Y0491997
X1178178Y0467337
X1178178Y0589857
X1178178Y0575684
X1170878Y0611117
X1170878Y0600344
X1170878Y0614517
X1170878Y0582771
X1170878Y0568597
X1178178Y0561510
X1170878Y0586171
X1170878Y0536131
X1178178Y0525644
X1178178Y0579084
X1178178Y0564910
X1170878Y0596944
X1170878Y0571997
X1178178Y0593257
X1178178Y0607430
X1170878Y0532731
X1178178Y0529044
X1178178Y0604030
X1576940Y0412255
X1584240Y0419341
X1576940Y0415655
X1584240Y0394395
X1576940Y0401482
X1584240Y0390995
X1584240Y0405168
X1576940Y0398082
X1584240Y0408568
X1635265Y0467337
X1635265Y0481510
X1627965Y0518558
X1627965Y0477824
X1627965Y0491997
X1635265Y0484910
X1635265Y0511471
X1627965Y0474424
X1635265Y0514871
X1635265Y0470737
X1627965Y0521958
X1627965Y0488597
X1584240Y0422741
X1576940Y0426428
X1576940Y0479868
X1576940Y0490641
X1576940Y0494041
X1584240Y0436915
X1584240Y0513515
X1584240Y0469381
X1584240Y0486954
X1576940Y0429828
X1584240Y0516915
X1584240Y0472781
X1576940Y0440602
X1576940Y0476468
X1584240Y0433515
X1576940Y0520602
X1584240Y0483554
X1576940Y0444002
X1635265Y0525644
X1635265Y0589857
X1627965Y0532731
X1635265Y0604030
X1627965Y0611117
X1635265Y0561510
X1635265Y0593257
X1635265Y0529044
X1627965Y0600344
X1627965Y0568597
X1627965Y0571997
X1627965Y0586171
X1627965Y0582771
X1635265Y0579084
X1627965Y0614517
X1635265Y0607430
X1635265Y0575684
X1627965Y0596944
X1635265Y0564910
X1627965Y0536131
X1584240Y0527688
X1576940Y0538175
X1584240Y0531088
X1576940Y0524002
X1576940Y0534775
M00
X0118543Y1616496
X0109882Y1612166
X0118543Y1611378
X0109882Y1607048
X0135866Y1616496
X0127205Y1612166
X0135866Y1611378
X0127205Y1607048
X0153189Y1616496
X0144528Y1612166
X0153189Y1611378
X0144528Y1607048
X0161850Y1612166
X0161850Y1607048
X0118543Y1514134
X0109882Y1509804
X0118543Y1509016
X0109882Y1504685
X0135866Y1514134
X0127205Y1509804
X0135866Y1509016
X0127205Y1504685
X0153189Y1514134
X0144528Y1509804
X0153189Y1509016
X0144528Y1504685
X0161850Y1509804
X0161850Y1504685
X0170512Y1514134
X0170512Y1509016
X0170512Y1616496
X0170512Y1611378
X0291771Y1585788
X0283110Y1581457
X0291771Y1580670
X0283110Y1576339
X0309094Y1585788
X0300433Y1581457
X0309094Y1580670
X0300433Y1576339
X0326417Y1585788
X0317756Y1581457
X0326417Y1580670
X0317756Y1576339
X0343740Y1585788
X0335078Y1581457
X0343740Y1580670
X0335078Y1576339
X0291771Y1468071
X0283110Y1463741
X0291771Y1462953
X0283110Y1458622
X0309094Y1468071
X0300433Y1463741
X0309094Y1462953
X0300433Y1458622
X0326417Y1468071
X0317756Y1463741
X0326417Y1462953
X0317756Y1458622
X0343740Y1468071
X0335078Y1463741
X0343740Y1462953
X0335078Y1458622
X0465000Y1483426
X0456339Y1479095
X0465000Y1478308
X0456339Y1473977
X0465000Y1570434
X0456339Y1566103
X0465000Y1565315
X0456339Y1560985
X0482323Y1570434
X0473662Y1566103
X0482323Y1565315
X0473662Y1560985
X0499646Y1570434
X0490985Y1566103
X0499646Y1565315
X0490985Y1560985
X0516969Y1570434
X0508307Y1566103
X0516969Y1565315
X0508307Y1560985
X0482323Y1483426
X0473662Y1479095
X0482323Y1478308
X0473662Y1473977
X0499646Y1483426
X0490985Y1479095
X0499646Y1478308
X0490985Y1473977
X0516969Y1483426
X0508307Y1479095
X0516969Y1478308
X0508307Y1473977
X0638228Y1498780
X0629567Y1494449
X0638228Y1493662
X0629567Y1489331
X0655551Y1498780
X0646890Y1494449
X0655551Y1493662
X0646890Y1489331
X0664213Y1494449
X0664213Y1489331
X0638228Y1601142
X0629567Y1596811
X0638228Y1596024
X0629567Y1591693
X0655551Y1601142
X0646890Y1596811
X0655551Y1596024
X0646890Y1591693
X0664213Y1596811
X0664213Y1591693
X0672874Y1601142
X0672874Y1596024
X0690197Y1601142
X0681535Y1596811
X0690197Y1596024
X0681535Y1591693
X0672874Y1498780
X0672874Y1493662
X0690197Y1498780
X0681535Y1494449
X0690197Y1493662
X0681535Y1489331
X1140511Y1616496
X1131850Y1612166
X1140511Y1611378
X1131850Y1607048
X1157834Y1616496
X1149173Y1612166
X1157834Y1611378
X1149173Y1607048
X1166496Y1612166
X1166496Y1607048
X1140511Y1514134
X1131850Y1509804
X1140511Y1509016
X1131850Y1504685
X1157834Y1514134
X1149173Y1509804
X1157834Y1509016
X1149173Y1504685
X1166496Y1509804
X1166496Y1504685
X1175157Y1514134
X1175157Y1509016
X1192480Y1514134
X1183818Y1509804
X1192480Y1509016
X1183818Y1504685
X1175157Y1616496
X1175157Y1611378
X1192480Y1616496
X1183818Y1612166
X1192480Y1611378
X1183818Y1607048
X1313740Y1585788
X1305079Y1581457
X1313740Y1580670
X1305079Y1576339
X1331063Y1585788
X1322402Y1581457
X1331063Y1580670
X1322402Y1576339
X1348386Y1585788
X1339725Y1581457
X1348386Y1580670
X1339725Y1576339
X1365709Y1585788
X1357047Y1581457
X1365709Y1580670
X1357047Y1576339
X1313740Y1468071
X1305079Y1463741
X1313740Y1462953
X1305079Y1458622
X1331063Y1468071
X1322402Y1463741
X1331063Y1462953
X1322402Y1458622
X1348386Y1468071
X1339725Y1463741
X1348386Y1462953
X1339725Y1458622
X1365709Y1468071
X1357047Y1463741
X1365709Y1462953
X1357047Y1458622
X1486968Y1570434
X1478307Y1566103
X1486968Y1565315
X1478307Y1560985
X1504291Y1570434
X1495630Y1566103
X1504291Y1565315
X1495630Y1560985
X1521614Y1570434
X1512953Y1566103
X1521614Y1565315
X1512953Y1560985
X1538937Y1570434
X1530275Y1566103
X1538937Y1565315
X1530275Y1560985
X1486968Y1483426
X1478307Y1479095
X1486968Y1478308
X1478307Y1473977
X1504291Y1483426
X1495630Y1479095
X1504291Y1478308
X1495630Y1473977
X1521614Y1483426
X1512953Y1479095
X1521614Y1478308
X1512953Y1473977
X1538937Y1483426
X1530275Y1479095
X1538937Y1478308
X1530275Y1473977
X1660196Y1498780
X1651535Y1494449
X1660196Y1493662
X1651535Y1489331
X1668858Y1494449
X1668858Y1489331
X1660196Y1601142
X1651535Y1596811
X1660196Y1596024
X1651535Y1591693
X1668858Y1596811
X1668858Y1591693
X1677519Y1601142
X1677519Y1596024
X1694842Y1601142
X1686181Y1596811
X1694842Y1596024
X1686181Y1591693
X1712165Y1601142
X1703503Y1596811
X1712165Y1596024
X1703503Y1591693
X1677519Y1498780
X1677519Y1493662
X1694842Y1498780
X1686181Y1494449
X1694842Y1493662
X1686181Y1489331
X1712165Y1498780
X1703503Y1494449
X1712165Y1493662
X1703503Y1489331
M30
